(kicad_pcb
	(version 20260206)
	(generator "pcbnew")
	(generator_version "10.0")
	(general
		(thickness 1.6)
		(legacy_teardrops no)
	)
	(paper "A4")
	(title_block
		(title "03242023_DA0F0TMBIJ0_F0T_Motherboard_J_brd_V01_OCP.brd")
		(comment 1 "Grand Teton / footprint 2539 of 6105 (J25), pads 113-224 of 291")
	)
	(layers
		(0 "F.Cu" signal "TOP")
		(4 "In1.Cu" signal "GND")
		(6 "In2.Cu" signal "IN1")
		(8 "In3.Cu" signal "GND1")
		(10 "In4.Cu" signal "IN2")
		(12 "In5.Cu" signal "GND2")
		(14 "In6.Cu" signal "IN3")
		(16 "In7.Cu" signal "GND3")
		(18 "In8.Cu" signal "VCC")
		(20 "In9.Cu" signal "VCC1")
		(22 "In10.Cu" signal "GND4")
		(24 "In11.Cu" signal "IN4")
		(26 "In12.Cu" signal "GND5")
		(28 "In13.Cu" signal "IN5")
		(30 "In14.Cu" signal "GND6")
		(32 "In15.Cu" signal "IN6")
		(34 "In16.Cu" signal "GND7")
		(2 "B.Cu" signal "BOTTOM")
		(9 "F.Adhes" user "F.Adhesive")
		(11 "B.Adhes" user "B.Adhesive")
		(13 "F.Paste" user "Package Geometry/Pastemask Top")
		(15 "B.Paste" user "Package Geometry/Pastemask Bottom")
		(5 "F.SilkS" user "Ref Des/Silkscreen Top")
		(7 "B.SilkS" user "Ref Des/Silkscreen Bottom")
		(1 "F.Mask" user "Board Geometry/Soldermask Top")
		(3 "B.Mask" user "Board Geometry/Soldermask Bottom")
		(17 "Dwgs.User" user "User.Drawings")
		(19 "Cmts.User" user "User.Comments")
		(21 "Eco1.User" user "User.Eco1")
		(23 "Eco2.User" user "User.Eco2")
		(25 "Edge.Cuts" user "Board Geometry/Outline")
		(27 "Margin" user)
		(31 "F.CrtYd" user "Package Geometry/Place Bound Top")
		(29 "B.CrtYd" user "Package Geometry/Place Bound Bottom")
		(35 "F.Fab" user "Ref Des/Assembly Top")
		(33 "B.Fab" user "Ref Des/Assembly Bottom")
	)
	(footprint ""
		(layer "F.Cu")
		(at 168.40708 -258.091686)
		(property "Reference" "J25"
			(at -3.683 -81.702148 0)
			(unlocked yes)
			(layer "F.SilkS")
			(effects
				(font
					(size 0.7874 0.5842)
					(thickness 0.1524)
				)
				(justify left)
			)
		)
		(property "Value" ""
			(at 0 0 0)
			(layer "F.Fab")
			(effects
				(font
					(size 1.27 1.27)
				)
			)
		)
		(duplicate_pad_numbers_are_jumpers no)
		(pad "113" smd rect
			(at -2.050034 36.975034 270)
			(size 0.519938 1.4986)
			(layers "F.Cu" "F.Mask" "F.Paste")
			(net "M_E_CPU1_SB_DQ<9>")
		)
		(pad "114" smd rect
			(at -2.050034 37.824918 270)
			(size 0.519938 1.4986)
			(layers "F.Cu" "F.Mask" "F.Paste")
			(net "GND")
		)
		(pad "115" smd rect
			(at -2.050034 38.675056 270)
			(size 0.519938 1.4986)
			(layers "F.Cu" "F.Mask" "F.Paste")
			(net "M_E_CPU1_SB_DQS_DP<1>")
		)
		(pad "116" smd rect
			(at -2.050034 39.52494 270)
			(size 0.519938 1.4986)
			(layers "F.Cu" "F.Mask" "F.Paste")
			(net "M_E_CPU1_SB_DQS_DN<1>")
		)
		(pad "117" smd rect
			(at -2.050034 40.375078 270)
			(size 0.519938 1.4986)
			(layers "F.Cu" "F.Mask" "F.Paste")
			(net "GND")
		)
		(pad "118" smd rect
			(at -2.050034 41.224962 270)
			(size 0.519938 1.4986)
			(layers "F.Cu" "F.Mask" "F.Paste")
			(net "M_E_CPU1_SB_DQ<12>")
		)
		(pad "119" smd rect
			(at -2.050034 42.0751 270)
			(size 0.519938 1.4986)
			(layers "F.Cu" "F.Mask" "F.Paste")
			(net "GND")
		)
		(pad "120" smd rect
			(at -2.050034 42.924984 270)
			(size 0.519938 1.4986)
			(layers "F.Cu" "F.Mask" "F.Paste")
			(net "M_E_CPU1_SB_DQ<13>")
		)
		(pad "121" smd rect
			(at -2.050034 43.775122 270)
			(size 0.519938 1.4986)
			(layers "F.Cu" "F.Mask" "F.Paste")
			(net "GND")
		)
		(pad "122" smd rect
			(at -2.050034 44.625006 270)
			(size 0.519938 1.4986)
			(layers "F.Cu" "F.Mask" "F.Paste")
			(net "M_E_CPU1_SB_DQ<16>")
		)
		(pad "123" smd rect
			(at -2.050034 45.47489 270)
			(size 0.519938 1.4986)
			(layers "F.Cu" "F.Mask" "F.Paste")
			(net "GND")
		)
		(pad "124" smd rect
			(at -2.050034 46.325028 270)
			(size 0.519938 1.4986)
			(layers "F.Cu" "F.Mask" "F.Paste")
			(net "M_E_CPU1_SB_DQ<17>")
		)
		(pad "125" smd rect
			(at -2.050034 47.174912 270)
			(size 0.519938 1.4986)
			(layers "F.Cu" "F.Mask" "F.Paste")
			(net "GND")
		)
		(pad "126" smd rect
			(at -2.050034 48.02505 270)
			(size 0.519938 1.4986)
			(layers "F.Cu" "F.Mask" "F.Paste")
			(net "M_E_CPU1_SB_DQS_DP<2>")
		)
		(pad "127" smd rect
			(at -2.050034 48.874934 270)
			(size 0.519938 1.4986)
			(layers "F.Cu" "F.Mask" "F.Paste")
			(net "M_E_CPU1_SB_DQS_DN<2>")
		)
		(pad "128" smd rect
			(at -2.050034 49.725072 270)
			(size 0.519938 1.4986)
			(layers "F.Cu" "F.Mask" "F.Paste")
			(net "GND")
		)
		(pad "129" smd rect
			(at -2.050034 50.574956 270)
			(size 0.519938 1.4986)
			(layers "F.Cu" "F.Mask" "F.Paste")
			(net "M_E_CPU1_SB_DQ<20>")
		)
		(pad "130" smd rect
			(at -2.050034 51.425094 270)
			(size 0.519938 1.4986)
			(layers "F.Cu" "F.Mask" "F.Paste")
			(net "GND")
		)
		(pad "131" smd rect
			(at -2.050034 52.274978 270)
			(size 0.519938 1.4986)
			(layers "F.Cu" "F.Mask" "F.Paste")
			(net "M_E_CPU1_SB_DQ<21>")
		)
		(pad "132" smd rect
			(at -2.050034 53.125116 270)
			(size 0.519938 1.4986)
			(layers "F.Cu" "F.Mask" "F.Paste")
			(net "GND")
		)
		(pad "133" smd rect
			(at -2.050034 53.975 270)
			(size 0.519938 1.4986)
			(layers "F.Cu" "F.Mask" "F.Paste")
			(net "M_E_CPU1_SB_DQ<24>")
		)
		(pad "134" smd rect
			(at -2.050034 54.824884 270)
			(size 0.519938 1.4986)
			(layers "F.Cu" "F.Mask" "F.Paste")
			(net "GND")
		)
		(pad "135" smd rect
			(at -2.050034 55.675022 270)
			(size 0.519938 1.4986)
			(layers "F.Cu" "F.Mask" "F.Paste")
			(net "M_E_CPU1_SB_DQ<25>")
		)
		(pad "136" smd rect
			(at -2.050034 56.524906 270)
			(size 0.519938 1.4986)
			(layers "F.Cu" "F.Mask" "F.Paste")
			(net "GND")
		)
		(pad "137" smd rect
			(at -2.050034 57.375044 270)
			(size 0.519938 1.4986)
			(layers "F.Cu" "F.Mask" "F.Paste")
			(net "M_E_CPU1_SB_DQS_DP<3>")
		)
		(pad "138" smd rect
			(at -2.050034 58.224928 270)
			(size 0.519938 1.4986)
			(layers "F.Cu" "F.Mask" "F.Paste")
			(net "M_E_CPU1_SB_DQS_DN<3>")
		)
		(pad "139" smd rect
			(at -2.050034 59.075066 270)
			(size 0.519938 1.4986)
			(layers "F.Cu" "F.Mask" "F.Paste")
			(net "GND")
		)
		(pad "140" smd rect
			(at -2.050034 59.92495 270)
			(size 0.519938 1.4986)
			(layers "F.Cu" "F.Mask" "F.Paste")
			(net "M_E_CPU1_SB_DQ<28>")
		)
		(pad "141" smd rect
			(at -2.050034 60.775088 270)
			(size 0.519938 1.4986)
			(layers "F.Cu" "F.Mask" "F.Paste")
			(net "GND")
		)
		(pad "142" smd rect
			(at -2.050034 61.624972 270)
			(size 0.519938 1.4986)
			(layers "F.Cu" "F.Mask" "F.Paste")
			(net "M_E_CPU1_SB_DQ<29>")
		)
		(pad "143" smd rect
			(at -2.050034 62.47511 270)
			(size 0.519938 1.4986)
			(layers "F.Cu" "F.Mask" "F.Paste")
			(net "GND")
		)
		(pad "144" smd rect
			(at -2.050034 63.324994 270)
			(size 0.519938 1.4986)
			(layers "F.Cu" "F.Mask" "F.Paste")
			(net "TP_CHE_CPU1_DIMM1_FRU_1")
		)
		(pad "145" smd rect
			(at 2.050034 -63.324994 270)
			(size 0.519938 1.4986)
			(layers "F.Cu" "F.Mask" "F.Paste")
			(net "P12V_S3_AUX_CPU1_NVDIMM")
		)
		(pad "146" smd rect
			(at 2.050034 -62.47511 270)
			(size 0.519938 1.4986)
			(layers "F.Cu" "F.Mask" "F.Paste")
			(net "P12V_S3_AUX_CPU1_NVDIMM")
		)
		(pad "147" smd rect
			(at 2.050034 -61.624972 270)
			(size 0.519938 1.4986)
			(layers "F.Cu" "F.Mask" "F.Paste")
			(net "PWRGD_CHE_CPU1_DIMM1")
		)
		(pad "148" smd rect
			(at 2.050034 -60.775088 270)
			(size 0.519938 1.4986)
			(layers "F.Cu" "F.Mask" "F.Paste")
			(net "PD_CHE_CPU1_DIMM1_SAA")
		)
		(pad "149" smd rect
			(at 2.050034 -59.92495 270)
			(size 0.519938 1.4986)
			(layers "F.Cu" "F.Mask" "F.Paste")
			(net "TP_CHE_CPU1_DIMM1_FRU_2")
		)
		(pad "150" smd rect
			(at 2.050034 -59.075066 270)
			(size 0.519938 1.4986)
			(layers "F.Cu" "F.Mask" "F.Paste")
			(net "TP_CHE_CPU1_DIMM1_FRU_3")
		)
		(pad "151" smd rect
			(at 2.050034 -58.224928 270)
			(size 0.519938 1.4986)
			(layers "F.Cu" "F.Mask" "F.Paste")
			(net "GND")
		)
		(pad "152" smd rect
			(at 2.050034 -57.375044 270)
			(size 0.519938 1.4986)
			(layers "F.Cu" "F.Mask" "F.Paste")
			(net "M_E_CPU1_SA_DQ<2>")
		)
		(pad "153" smd rect
			(at 2.050034 -56.524906 270)
			(size 0.519938 1.4986)
			(layers "F.Cu" "F.Mask" "F.Paste")
			(net "GND")
		)
		(pad "154" smd rect
			(at 2.050034 -55.675022 270)
			(size 0.519938 1.4986)
			(layers "F.Cu" "F.Mask" "F.Paste")
			(net "M_E_CPU1_SA_DQ<3>")
		)
		(pad "155" smd rect
			(at 2.050034 -54.824884 270)
			(size 0.519938 1.4986)
			(layers "F.Cu" "F.Mask" "F.Paste")
			(net "GND")
		)
		(pad "156" smd rect
			(at 2.050034 -53.975 270)
			(size 0.519938 1.4986)
			(layers "F.Cu" "F.Mask" "F.Paste")
			(net "M_E_CPU1_SA_DQS_DN<5>")
		)
		(pad "157" smd rect
			(at 2.050034 -53.125116 270)
			(size 0.519938 1.4986)
			(layers "F.Cu" "F.Mask" "F.Paste")
			(net "M_E_CPU1_SA_DQS_DP<5>")
		)
		(pad "158" smd rect
			(at 2.050034 -52.274978 270)
			(size 0.519938 1.4986)
			(layers "F.Cu" "F.Mask" "F.Paste")
			(net "GND")
		)
		(pad "159" smd rect
			(at 2.050034 -51.425094 270)
			(size 0.519938 1.4986)
			(layers "F.Cu" "F.Mask" "F.Paste")
			(net "M_E_CPU1_SA_DQ<6>")
		)
		(pad "160" smd rect
			(at 2.050034 -50.574956 270)
			(size 0.519938 1.4986)
			(layers "F.Cu" "F.Mask" "F.Paste")
			(net "GND")
		)
		(pad "161" smd rect
			(at 2.050034 -49.725072 270)
			(size 0.519938 1.4986)
			(layers "F.Cu" "F.Mask" "F.Paste")
			(net "M_E_CPU1_SA_DQ<7>")
		)
		(pad "162" smd rect
			(at 2.050034 -48.874934 270)
			(size 0.519938 1.4986)
			(layers "F.Cu" "F.Mask" "F.Paste")
			(net "GND")
		)
		(pad "163" smd rect
			(at 2.050034 -48.02505 270)
			(size 0.519938 1.4986)
			(layers "F.Cu" "F.Mask" "F.Paste")
			(net "M_E_CPU1_SA_DQ<10>")
		)
		(pad "164" smd rect
			(at 2.050034 -47.174912 270)
			(size 0.519938 1.4986)
			(layers "F.Cu" "F.Mask" "F.Paste")
			(net "GND")
		)
		(pad "165" smd rect
			(at 2.050034 -46.325028 270)
			(size 0.519938 1.4986)
			(layers "F.Cu" "F.Mask" "F.Paste")
			(net "M_E_CPU1_SA_DQ<11>")
		)
		(pad "166" smd rect
			(at 2.050034 -45.47489 270)
			(size 0.519938 1.4986)
			(layers "F.Cu" "F.Mask" "F.Paste")
			(net "GND")
		)
		(pad "167" smd rect
			(at 2.050034 -44.625006 270)
			(size 0.519938 1.4986)
			(layers "F.Cu" "F.Mask" "F.Paste")
			(net "M_E_CPU1_SA_DQS_DN<6>")
		)
		(pad "168" smd rect
			(at 2.050034 -43.775122 270)
			(size 0.519938 1.4986)
			(layers "F.Cu" "F.Mask" "F.Paste")
			(net "M_E_CPU1_SA_DQS_DP<6>")
		)
		(pad "169" smd rect
			(at 2.050034 -42.924984 270)
			(size 0.519938 1.4986)
			(layers "F.Cu" "F.Mask" "F.Paste")
			(net "GND")
		)
		(pad "170" smd rect
			(at 2.050034 -42.0751 270)
			(size 0.519938 1.4986)
			(layers "F.Cu" "F.Mask" "F.Paste")
			(net "M_E_CPU1_SA_DQ<14>")
		)
		(pad "171" smd rect
			(at 2.050034 -41.224962 270)
			(size 0.519938 1.4986)
			(layers "F.Cu" "F.Mask" "F.Paste")
			(net "GND")
		)
		(pad "172" smd rect
			(at 2.050034 -40.375078 270)
			(size 0.519938 1.4986)
			(layers "F.Cu" "F.Mask" "F.Paste")
			(net "M_E_CPU1_SA_DQ<15>")
		)
		(pad "173" smd rect
			(at 2.050034 -39.52494 270)
			(size 0.519938 1.4986)
			(layers "F.Cu" "F.Mask" "F.Paste")
			(net "GND")
		)
		(pad "174" smd rect
			(at 2.050034 -38.675056 270)
			(size 0.519938 1.4986)
			(layers "F.Cu" "F.Mask" "F.Paste")
			(net "M_E_CPU1_SA_DQ<18>")
		)
		(pad "175" smd rect
			(at 2.050034 -37.824918 270)
			(size 0.519938 1.4986)
			(layers "F.Cu" "F.Mask" "F.Paste")
			(net "GND")
		)
		(pad "176" smd rect
			(at 2.050034 -36.975034 270)
			(size 0.519938 1.4986)
			(layers "F.Cu" "F.Mask" "F.Paste")
			(net "M_E_CPU1_SA_DQ<19>")
		)
		(pad "177" smd rect
			(at 2.050034 -36.124896 270)
			(size 0.519938 1.4986)
			(layers "F.Cu" "F.Mask" "F.Paste")
			(net "GND")
		)
		(pad "178" smd rect
			(at 2.050034 -35.275012 270)
			(size 0.519938 1.4986)
			(layers "F.Cu" "F.Mask" "F.Paste")
			(net "M_E_CPU1_SA_DQS_DN<7>")
		)
		(pad "179" smd rect
			(at 2.050034 -34.425128 270)
			(size 0.519938 1.4986)
			(layers "F.Cu" "F.Mask" "F.Paste")
			(net "M_E_CPU1_SA_DQS_DP<7>")
		)
		(pad "180" smd rect
			(at 2.050034 -33.57499 270)
			(size 0.519938 1.4986)
			(layers "F.Cu" "F.Mask" "F.Paste")
			(net "GND")
		)
		(pad "181" smd rect
			(at 2.050034 -32.725106 270)
			(size 0.519938 1.4986)
			(layers "F.Cu" "F.Mask" "F.Paste")
			(net "M_E_CPU1_SA_DQ<22>")
		)
		(pad "182" smd rect
			(at 2.050034 -31.874968 270)
			(size 0.519938 1.4986)
			(layers "F.Cu" "F.Mask" "F.Paste")
			(net "GND")
		)
		(pad "183" smd rect
			(at 2.050034 -31.025084 270)
			(size 0.519938 1.4986)
			(layers "F.Cu" "F.Mask" "F.Paste")
			(net "M_E_CPU1_SA_DQ<23>")
		)
		(pad "184" smd rect
			(at 2.050034 -30.174946 270)
			(size 0.519938 1.4986)
			(layers "F.Cu" "F.Mask" "F.Paste")
			(net "GND")
		)
		(pad "185" smd rect
			(at 2.050034 -29.325062 270)
			(size 0.519938 1.4986)
			(layers "F.Cu" "F.Mask" "F.Paste")
			(net "M_E_CPU1_SA_DQ<26>")
		)
		(pad "186" smd rect
			(at 2.050034 -28.474924 270)
			(size 0.519938 1.4986)
			(layers "F.Cu" "F.Mask" "F.Paste")
			(net "GND")
		)
		(pad "187" smd rect
			(at 2.050034 -27.62504 270)
			(size 0.519938 1.4986)
			(layers "F.Cu" "F.Mask" "F.Paste")
			(net "M_E_CPU1_SA_DQ<27>")
		)
		(pad "188" smd rect
			(at 2.050034 -26.774902 270)
			(size 0.519938 1.4986)
			(layers "F.Cu" "F.Mask" "F.Paste")
			(net "GND")
		)
		(pad "189" smd rect
			(at 2.050034 -25.925018 270)
			(size 0.519938 1.4986)
			(layers "F.Cu" "F.Mask" "F.Paste")
			(net "M_E_CPU1_SA_DQS_DN<8>")
		)
		(pad "190" smd rect
			(at 2.050034 -25.07488 270)
			(size 0.519938 1.4986)
			(layers "F.Cu" "F.Mask" "F.Paste")
			(net "M_E_CPU1_SA_DQS_DP<8>")
		)
		(pad "191" smd rect
			(at 2.050034 -24.224996 270)
			(size 0.519938 1.4986)
			(layers "F.Cu" "F.Mask" "F.Paste")
			(net "GND")
		)
		(pad "192" smd rect
			(at 2.050034 -23.375112 270)
			(size 0.519938 1.4986)
			(layers "F.Cu" "F.Mask" "F.Paste")
			(net "M_E_CPU1_SA_DQ<30>")
		)
		(pad "193" smd rect
			(at 2.050034 -22.524974 270)
			(size 0.519938 1.4986)
			(layers "F.Cu" "F.Mask" "F.Paste")
			(net "GND")
		)
		(pad "194" smd rect
			(at 2.050034 -21.67509 270)
			(size 0.519938 1.4986)
			(layers "F.Cu" "F.Mask" "F.Paste")
			(net "M_E_CPU1_SA_DQ<31>")
		)
		(pad "195" smd rect
			(at 2.050034 -20.824952 270)
			(size 0.519938 1.4986)
			(layers "F.Cu" "F.Mask" "F.Paste")
			(net "GND")
		)
		(pad "196" smd rect
			(at 2.050034 -19.975068 270)
			(size 0.519938 1.4986)
			(layers "F.Cu" "F.Mask" "F.Paste")
			(net "M_E_CPU1_SA_CB<2>")
		)
		(pad "197" smd rect
			(at 2.050034 -19.12493 270)
			(size 0.519938 1.4986)
			(layers "F.Cu" "F.Mask" "F.Paste")
			(net "GND")
		)
		(pad "198" smd rect
			(at 2.050034 -18.275046 270)
			(size 0.519938 1.4986)
			(layers "F.Cu" "F.Mask" "F.Paste")
			(net "M_E_CPU1_SA_CB<3>")
		)
		(pad "199" smd rect
			(at 2.050034 -17.424908 270)
			(size 0.519938 1.4986)
			(layers "F.Cu" "F.Mask" "F.Paste")
			(net "GND")
		)
		(pad "200" smd rect
			(at 2.050034 -16.575024 270)
			(size 0.519938 1.4986)
			(layers "F.Cu" "F.Mask" "F.Paste")
			(net "M_E_CPU1_SA_DQS_DN<9>")
		)
		(pad "201" smd rect
			(at 2.050034 -15.724886 270)
			(size 0.519938 1.4986)
			(layers "F.Cu" "F.Mask" "F.Paste")
			(net "M_E_CPU1_SA_DQS_DP<9>")
		)
		(pad "202" smd rect
			(at 2.050034 -14.875002 270)
			(size 0.519938 1.4986)
			(layers "F.Cu" "F.Mask" "F.Paste")
			(net "GND")
		)
		(pad "203" smd rect
			(at 2.050034 -14.025118 270)
			(size 0.519938 1.4986)
			(layers "F.Cu" "F.Mask" "F.Paste")
			(net "M_E_CPU1_SA_CB<6>")
		)
		(pad "204" smd rect
			(at 2.050034 -13.17498 270)
			(size 0.519938 1.4986)
			(layers "F.Cu" "F.Mask" "F.Paste")
			(net "GND")
		)
		(pad "205" smd rect
			(at 2.050034 -12.325096 270)
			(size 0.519938 1.4986)
			(layers "F.Cu" "F.Mask" "F.Paste")
			(net "M_E_CPU1_SA_CB<7>")
		)
		(pad "206" smd rect
			(at 2.050034 -11.474958 270)
			(size 0.519938 1.4986)
			(layers "F.Cu" "F.Mask" "F.Paste")
			(net "GND")
		)
		(pad "207" smd rect
			(at 2.050034 -10.625074 270)
			(size 0.519938 1.4986)
			(layers "F.Cu" "F.Mask" "F.Paste")
			(net "RST_M_EF_CPU1_FPGA_N")
		)
		(pad "208" smd rect
			(at 2.050034 -9.774936 270)
			(size 0.519938 1.4986)
			(layers "F.Cu" "F.Mask" "F.Paste")
			(net "GND")
		)
		(pad "209" smd rect
			(at 2.050034 -8.925052 270)
			(size 0.519938 1.4986)
			(layers "F.Cu" "F.Mask" "F.Paste")
			(net "M_E_CPU1_SA_CS_N<1>")
		)
		(pad "210" smd rect
			(at 2.050034 -8.074914 270)
			(size 0.519938 1.4986)
			(layers "F.Cu" "F.Mask" "F.Paste")
			(net "GND")
		)
		(pad "211" smd rect
			(at 2.050034 -7.22503 270)
			(size 0.519938 1.4986)
			(layers "F.Cu" "F.Mask" "F.Paste")
			(net "M_E_CPU1_SA_CA<1>")
		)
		(pad "212" smd rect
			(at 2.050034 -6.374892 270)
			(size 0.519938 1.4986)
			(layers "F.Cu" "F.Mask" "F.Paste")
			(net "GND")
		)
		(pad "213" smd rect
			(at 2.050034 -5.525008 270)
			(size 0.519938 1.4986)
			(layers "F.Cu" "F.Mask" "F.Paste")
			(net "M_E_CPU1_SA_CA<3>")
		)
		(pad "214" smd rect
			(at 2.050034 -4.675124 270)
			(size 0.519938 1.4986)
			(layers "F.Cu" "F.Mask" "F.Paste")
			(net "GND")
		)
		(pad "215" smd rect
			(at 2.050034 -3.824986 270)
			(size 0.519938 1.4986)
			(layers "F.Cu" "F.Mask" "F.Paste")
			(net "M_E_CPU1_SA_CA<5>")
		)
		(pad "216" smd rect
			(at 2.050034 -2.975102 270)
			(size 0.519938 1.4986)
			(layers "F.Cu" "F.Mask" "F.Paste")
			(net "GND")
		)
		(pad "217" smd rect
			(at 2.050034 -2.124964 270)
			(size 0.519938 1.4986)
			(layers "F.Cu" "F.Mask" "F.Paste")
			(net "M_E_CPU1_CLK_DP<0>")
		)
		(pad "218" smd rect
			(at 2.050034 -1.27508 270)
			(size 0.519938 1.4986)
			(layers "F.Cu" "F.Mask" "F.Paste")
			(net "M_E_CPU1_CLK_DN<0>")
		)
		(pad "219" smd rect
			(at 2.050034 -0.424942 270)
			(size 0.519938 1.4986)
			(layers "F.Cu" "F.Mask" "F.Paste")
			(net "GND")
		)
		(pad "220" smd rect
			(at 2.050034 5.525008 270)
			(size 0.519938 1.4986)
			(layers "F.Cu" "F.Mask" "F.Paste")
			(net "TP_CHE_CPU1_DIMM1_FRU_4")
		)
		(pad "221" smd rect
			(at 2.050034 6.374892 270)
			(size 0.519938 1.4986)
			(layers "F.Cu" "F.Mask" "F.Paste")
			(net "M_E_CPU1_SB_CA<1>")
		)
		(pad "222" smd rect
			(at 2.050034 7.22503 270)
			(size 0.519938 1.4986)
			(layers "F.Cu" "F.Mask" "F.Paste")
			(net "GND")
		)
		(pad "223" smd rect
			(at 2.050034 8.074914 270)
			(size 0.519938 1.4986)
			(layers "F.Cu" "F.Mask" "F.Paste")
			(net "M_E_CPU1_SB_CA<3>")
		)
		(pad "224" smd rect
			(at 2.050034 8.925052 270)
			(size 0.519938 1.4986)
			(layers "F.Cu" "F.Mask" "F.Paste")
			(net "GND")
		)
	)
)
